(kicad_pcb
	(version 20260206)
	(generator "pcbnew")
	(generator_version "10.0")
	(general
		(thickness 1.6)
		(legacy_teardrops no)
	)
	(paper "A4")
	(title_block
		(title "03242023_DA0F0TMBIJ0_F0T_Motherboard_J_brd_V01_OCP.brd")
		(comment 1 "Grand Teton / footprint 3039 of 6105 (U2), pads 2695-2805 of 4677")
	)
	(layers
		(0 "F.Cu" signal "TOP")
		(4 "In1.Cu" signal "GND")
		(6 "In2.Cu" signal "IN1")
		(8 "In3.Cu" signal "GND1")
		(10 "In4.Cu" signal "IN2")
		(12 "In5.Cu" signal "GND2")
		(14 "In6.Cu" signal "IN3")
		(16 "In7.Cu" signal "GND3")
		(18 "In8.Cu" signal "VCC")
		(20 "In9.Cu" signal "VCC1")
		(22 "In10.Cu" signal "GND4")
		(24 "In11.Cu" signal "IN4")
		(26 "In12.Cu" signal "GND5")
		(28 "In13.Cu" signal "IN5")
		(30 "In14.Cu" signal "GND6")
		(32 "In15.Cu" signal "IN6")
		(34 "In16.Cu" signal "GND7")
		(2 "B.Cu" signal "BOTTOM")
		(9 "F.Adhes" user "F.Adhesive")
		(11 "B.Adhes" user "B.Adhesive")
		(13 "F.Paste" user "Package Geometry/Pastemask Top")
		(15 "B.Paste" user "Package Geometry/Pastemask Bottom")
		(5 "F.SilkS" user "Ref Des/Silkscreen Top")
		(7 "B.SilkS" user "Ref Des/Silkscreen Bottom")
		(1 "F.Mask" user "Board Geometry/Soldermask Top")
		(3 "B.Mask" user "Board Geometry/Soldermask Bottom")
		(17 "Dwgs.User" user "User.Drawings")
		(19 "Cmts.User" user "User.Comments")
		(21 "Eco1.User" user "User.Eco1")
		(23 "Eco2.User" user "User.Eco2")
		(25 "Edge.Cuts" user "Board Geometry/Outline")
		(27 "Margin" user)
		(31 "F.CrtYd" user "Package Geometry/Place Bound Top")
		(29 "B.CrtYd" user "Package Geometry/Place Bound Bottom")
		(35 "F.Fab" user "Ref Des/Assembly Top")
		(33 "B.Fab" user "Ref Des/Assembly Bottom")
	)
	(footprint ""
		(layer "F.Cu")
		(at 359.870248 -251.76988 90)
		(property "Reference" "U2"
			(at -74.416158 -44.488608 0)
			(unlocked yes)
			(layer "F.SilkS")
			(effects
				(font
					(size 1.6002 1.1938)
					(thickness 0.1524)
				)
				(justify left)
			)
		)
		(property "Value" ""
			(at 0 0 90)
			(layer "F.Fab")
			(effects
				(font
					(size 1.27 1.27)
				)
			)
		)
		(duplicate_pad_numbers_are_jumpers no)
		(pad "DG70" smd circle
			(at 20.333462 13.447268 270)
			(size 0.4318 0.4318)
			(layers "F.Cu" "F.Mask" "F.Paste")
			(net "GND")
		)
		(pad "DG72" smd circle
			(at 21.961094 13.447268 270)
			(size 0.4318 0.4318)
			(layers "F.Cu" "F.Mask" "F.Paste")
			(net "M_H_CPU0_SA_DQ<14>")
		)
		(pad "DG74" smd circle
			(at 23.58898 13.447268 270)
			(size 0.4318 0.4318)
			(layers "F.Cu" "F.Mask" "F.Paste")
			(net "M_H_CPU0_SA_DQ<11>")
		)
		(pad "DG76" smd circle
			(at 25.216612 13.447268 270)
			(size 0.4318 0.4318)
			(layers "F.Cu" "F.Mask" "F.Paste")
			(net "GND")
		)
		(pad "DG78" smd circle
			(at 26.844498 13.447268 270)
			(size 0.4318 0.4318)
			(layers "F.Cu" "F.Mask" "F.Paste")
			(net "GND")
		)
		(pad "DG80" smd circle
			(at 28.472384 13.447268 270)
			(size 0.4318 0.4318)
			(layers "F.Cu" "F.Mask" "F.Paste")
			(net "GND")
		)
		(pad "DG82" smd circle
			(at 30.100016 13.447268 270)
			(size 0.4318 0.4318)
			(layers "F.Cu" "F.Mask" "F.Paste")
			(net "GND")
		)
		(pad "DG84" smd circle
			(at 31.727902 13.447268 270)
			(size 0.4318 0.4318)
			(layers "F.Cu" "F.Mask" "F.Paste")
			(net "GND")
		)
		(pad "DG86" smd circle
			(at 33.355534 13.447268 270)
			(size 0.4318 0.4318)
			(layers "F.Cu" "F.Mask" "F.Paste")
			(net "P5E_CPU0_PE3_TX_DP<9>")
		)
		(pad "DG88" smd circle
			(at 34.98342 13.447268 270)
			(size 0.4318 0.4318)
			(layers "F.Cu" "F.Mask" "F.Paste")
			(net "GND")
		)
		(pad "DG90" smd circle
			(at 36.611306 13.447268 270)
			(size 0.4318 0.4318)
			(layers "F.Cu" "F.Mask" "F.Paste")
			(net "P5E_CPU0_PE3_RX_DN<10>")
		)
		(pad "DH2" smd circle
			(at -36.611306 13.806932 270)
			(size 0.4318 0.4318)
			(layers "F.Cu" "F.Mask" "F.Paste")
			(net "UPI_CPU1_CPU0_P0P1_DP<10>")
		)
		(pad "DH4" smd circle
			(at -34.98342 13.806932 270)
			(size 0.4318 0.4318)
			(layers "F.Cu" "F.Mask" "F.Paste")
			(net "GND")
		)
		(pad "DH6" smd circle
			(at -33.355534 13.806932 270)
			(size 0.4318 0.4318)
			(layers "F.Cu" "F.Mask" "F.Paste")
			(net "UPI_CPU0_CPU1_P1P0_DN<9>")
		)
		(pad "DH8" smd circle
			(at -31.727902 13.806932 270)
			(size 0.4318 0.4318)
			(layers "F.Cu" "F.Mask" "F.Paste")
			(net "GND")
		)
		(pad "DH10" smd circle
			(at -30.100016 13.806932 270)
			(size 0.4318 0.4318)
			(layers "F.Cu" "F.Mask" "F.Paste")
			(net "P5E_CPU0_PE2_RX_DN<5>")
		)
		(pad "DH12" smd circle
			(at -28.472384 13.806932 270)
			(size 0.4318 0.4318)
			(layers "F.Cu" "F.Mask" "F.Paste")
			(net "GND")
		)
		(pad "DH14" smd circle
			(at -26.844498 13.806932 270)
			(size 0.4318 0.4318)
			(layers "F.Cu" "F.Mask" "F.Paste")
			(net "P5E_CPU0_PE2_TX_DP<6>")
		)
		(pad "DH16" smd circle
			(at -25.216612 13.806932 270)
			(size 0.4318 0.4318)
			(layers "F.Cu" "F.Mask" "F.Paste")
			(net "GND")
		)
		(pad "DH18" smd circle
			(at -23.58898 13.806932 270)
			(size 0.4318 0.4318)
			(layers "F.Cu" "F.Mask" "F.Paste")
			(net "M_H_CPU0_SB_DQS_DP<8>")
		)
		(pad "DH20" smd circle
			(at -21.961094 13.806932 270)
			(size 0.4318 0.4318)
			(layers "F.Cu" "F.Mask" "F.Paste")
			(net "GND")
		)
		(pad "DH22" smd circle
			(at -20.333462 13.806932 270)
			(size 0.4318 0.4318)
			(layers "F.Cu" "F.Mask" "F.Paste")
			(net "GND")
		)
		(pad "DH24" smd circle
			(at -18.705576 13.806932 270)
			(size 0.4318 0.4318)
			(layers "F.Cu" "F.Mask" "F.Paste")
			(net "M_H_CPU0_SB_DQS_DN<6>")
		)
		(pad "DH26" smd circle
			(at -17.07769 13.806932 270)
			(size 0.4318 0.4318)
			(layers "F.Cu" "F.Mask" "F.Paste")
			(net "GND")
		)
		(pad "DH28" smd circle
			(at -15.450058 13.806932 270)
			(size 0.4318 0.4318)
			(layers "F.Cu" "F.Mask" "F.Paste")
			(net "GND")
		)
		(pad "DH30" smd circle
			(at -13.822426 13.806932 270)
			(size 0.4318 0.4318)
			(layers "F.Cu" "F.Mask" "F.Paste")
			(net "M_H_CPU0_SB_DQS_DN<5>")
		)
		(pad "DH32" smd circle
			(at -12.19454 13.806932 270)
			(size 0.4318 0.4318)
			(layers "F.Cu" "F.Mask" "F.Paste")
			(net "GND")
		)
		(pad "DH34" smd circle
			(at -10.566654 13.806932 270)
			(size 0.4318 0.4318)
			(layers "F.Cu" "F.Mask" "F.Paste")
			(net "GND")
		)
		(pad "DH36" smd circle
			(at -8.939022 13.806932 270)
			(size 0.4318 0.4318)
			(layers "F.Cu" "F.Mask" "F.Paste")
			(net "M_H_CPU0_SB_DQS_DN<4>")
		)
		(pad "DH38" smd circle
			(at -7.311136 13.806932 270)
			(size 0.4318 0.4318)
			(layers "F.Cu" "F.Mask" "F.Paste")
			(net "GND")
		)
		(pad "DH40" smd circle
			(at -5.68325 13.806932 270)
			(size 0.4318 0.4318)
			(layers "F.Cu" "F.Mask" "F.Paste")
			(net "GND")
		)
		(pad "DH42" smd circle
			(at -4.055618 13.806932 270)
			(size 0.4318 0.4318)
			(layers "F.Cu" "F.Mask" "F.Paste")
			(net "M_H_CPU0_CLK_DN<0>")
		)
		(pad "DH44" smd circle
			(at -2.427732 13.806932 270)
			(size 0.4318 0.4318)
			(layers "F.Cu" "F.Mask" "F.Paste")
			(net "GND")
		)
		(pad "DH47" smd circle
			(at 1.613916 13.916914 270)
			(size 0.4318 0.4318)
			(layers "F.Cu" "F.Mask" "F.Paste")
			(net "GND")
		)
		(pad "DH49" smd circle
			(at 3.241802 13.916914 270)
			(size 0.4318 0.4318)
			(layers "F.Cu" "F.Mask" "F.Paste")
			(net "M_H_CPU0_SA_CA<1>")
		)
		(pad "DH51" smd circle
			(at 4.869434 13.916914 270)
			(size 0.4318 0.4318)
			(layers "F.Cu" "F.Mask" "F.Paste")
			(net "GND")
		)
		(pad "DH53" smd circle
			(at 6.49732 13.916914 270)
			(size 0.4318 0.4318)
			(layers "F.Cu" "F.Mask" "F.Paste")
			(net "GND")
		)
		(pad "DH55" smd circle
			(at 8.124952 13.916914 270)
			(size 0.4318 0.4318)
			(layers "F.Cu" "F.Mask" "F.Paste")
			(net "M_H_CPU0_SA_DQS_DN<9>")
		)
		(pad "DH57" smd circle
			(at 9.752838 13.916914 270)
			(size 0.4318 0.4318)
			(layers "F.Cu" "F.Mask" "F.Paste")
			(net "GND")
		)
		(pad "DH59" smd circle
			(at 11.380724 13.916914 270)
			(size 0.4318 0.4318)
			(layers "F.Cu" "F.Mask" "F.Paste")
			(net "GND")
		)
		(pad "DH61" smd circle
			(at 13.008356 13.916914 270)
			(size 0.4318 0.4318)
			(layers "F.Cu" "F.Mask" "F.Paste")
			(net "M_H_CPU0_SA_DQS_DN<8>")
		)
		(pad "DH63" smd circle
			(at 14.635988 13.916914 270)
			(size 0.4318 0.4318)
			(layers "F.Cu" "F.Mask" "F.Paste")
			(net "GND")
		)
		(pad "DH65" smd circle
			(at 16.263874 13.916914 270)
			(size 0.4318 0.4318)
			(layers "F.Cu" "F.Mask" "F.Paste")
			(net "GND")
		)
		(pad "DH67" smd circle
			(at 17.89176 13.916914 270)
			(size 0.4318 0.4318)
			(layers "F.Cu" "F.Mask" "F.Paste")
			(net "M_H_CPU0_SA_DQS_DN<7>")
		)
		(pad "DH69" smd circle
			(at 19.519392 13.916914 270)
			(size 0.4318 0.4318)
			(layers "F.Cu" "F.Mask" "F.Paste")
			(net "GND")
		)
		(pad "DH71" smd circle
			(at 21.147278 13.916914 270)
			(size 0.4318 0.4318)
			(layers "F.Cu" "F.Mask" "F.Paste")
			(net "GND")
		)
		(pad "DH73" smd circle
			(at 22.77491 13.916914 270)
			(size 0.4318 0.4318)
			(layers "F.Cu" "F.Mask" "F.Paste")
			(net "M_H_CPU0_SA_DQS_DN<6>")
		)
		(pad "DH75" smd circle
			(at 24.402796 13.916914 270)
			(size 0.4318 0.4318)
			(layers "F.Cu" "F.Mask" "F.Paste")
			(net "GND")
		)
		(pad "DH77" smd circle
			(at 26.030682 13.916914 270)
			(size 0.4318 0.4318)
			(layers "F.Cu" "F.Mask" "F.Paste")
			(net "GND")
		)
		(pad "DH79" smd circle
			(at 27.658314 13.916914 270)
			(size 0.4318 0.4318)
			(layers "F.Cu" "F.Mask" "F.Paste")
			(net "GND")
		)
		(pad "DH81" smd circle
			(at 29.2862 13.916914 270)
			(size 0.4318 0.4318)
			(layers "F.Cu" "F.Mask" "F.Paste")
			(net "GND")
		)
		(pad "DH83" smd circle
			(at 30.914086 13.916914 270)
			(size 0.4318 0.4318)
			(layers "F.Cu" "F.Mask" "F.Paste")
			(net "GND")
		)
		(pad "DH85" smd circle
			(at 32.541718 13.916914 270)
			(size 0.4318 0.4318)
			(layers "F.Cu" "F.Mask" "F.Paste")
			(net "GND")
		)
		(pad "DH87" smd circle
			(at 34.169604 13.916914 270)
			(size 0.4318 0.4318)
			(layers "F.Cu" "F.Mask" "F.Paste")
			(net "P5E_CPU0_PE3_TX_DN<8>")
		)
		(pad "DH89" smd circle
			(at 35.797236 13.916914 270)
			(size 0.4318 0.4318)
			(layers "F.Cu" "F.Mask" "F.Paste")
			(net "PVCCFA_EHV_FIVRA_CPU0")
		)
		(pad "DH91" smd oval
			(at 37.425122 13.916914)
			(size 0.381 0.4826)
			(drill
				(offset 0 -0.0508)
			)
			(layers "F.Cu" "F.Mask" "F.Paste")
			(net "P5E_CPU0_PE3_RX_DN<9>")
		)
		(pad "DJ1" smd oval
			(at -37.425122 14.277086 180)
			(size 0.381 0.4826)
			(drill
				(offset 0 -0.0508)
			)
			(layers "F.Cu" "F.Mask" "F.Paste")
			(net "UPI_CPU1_CPU0_P0P1_DN<9>")
		)
		(pad "DJ3" smd circle
			(at -35.797236 14.277086 270)
			(size 0.4318 0.4318)
			(layers "F.Cu" "F.Mask" "F.Paste")
			(net "PVCCINFAON_CPU0")
		)
		(pad "DJ5" smd circle
			(at -34.169604 14.277086 270)
			(size 0.4318 0.4318)
			(layers "F.Cu" "F.Mask" "F.Paste")
			(net "UPI_CPU0_CPU1_P1P0_DP<8>")
		)
		(pad "DJ7" smd circle
			(at -32.541718 14.277086 270)
			(size 0.4318 0.4318)
			(layers "F.Cu" "F.Mask" "F.Paste")
			(net "PVCCINFAON_CPU0")
		)
		(pad "DJ9" smd circle
			(at -30.914086 14.277086 270)
			(size 0.4318 0.4318)
			(layers "F.Cu" "F.Mask" "F.Paste")
			(net "P5E_CPU0_PE2_RX_DN<6>")
		)
		(pad "DJ11" smd circle
			(at -29.2862 14.277086 270)
			(size 0.4318 0.4318)
			(layers "F.Cu" "F.Mask" "F.Paste")
			(net "PVCCINFAON_CPU0")
		)
		(pad "DJ13" smd circle
			(at -27.658314 14.277086 270)
			(size 0.4318 0.4318)
			(layers "F.Cu" "F.Mask" "F.Paste")
			(net "P5E_CPU0_PE2_TX_DN<6>")
		)
		(pad "DJ15" smd circle
			(at -26.030682 14.277086 270)
			(size 0.4318 0.4318)
			(layers "F.Cu" "F.Mask" "F.Paste")
			(net "PVCCINFAON_CPU0")
		)
		(pad "DJ17" smd circle
			(at -24.402796 14.277086 270)
			(size 0.4318 0.4318)
			(layers "F.Cu" "F.Mask" "F.Paste")
			(net "M_H_CPU0_SB_DQ<30>")
		)
		(pad "DJ19" smd circle
			(at -22.77491 14.277086 270)
			(size 0.4318 0.4318)
			(layers "F.Cu" "F.Mask" "F.Paste")
			(net "GND")
		)
		(pad "DJ21" smd circle
			(at -21.147278 14.277086 270)
			(size 0.4318 0.4318)
			(layers "F.Cu" "F.Mask" "F.Paste")
			(net "M_H_CPU0_SB_DQS_DP<2>")
		)
		(pad "DJ23" smd circle
			(at -19.519392 14.277086 270)
			(size 0.4318 0.4318)
			(layers "F.Cu" "F.Mask" "F.Paste")
			(net "GND")
		)
		(pad "DJ25" smd circle
			(at -17.89176 14.277086 270)
			(size 0.4318 0.4318)
			(layers "F.Cu" "F.Mask" "F.Paste")
			(net "GND")
		)
		(pad "DJ27" smd circle
			(at -16.263874 14.277086 270)
			(size 0.4318 0.4318)
			(layers "F.Cu" "F.Mask" "F.Paste")
			(net "M_G_CPU0_SB_DQS_DN<1>")
		)
		(pad "DJ29" smd circle
			(at -14.635988 14.277086 270)
			(size 0.4318 0.4318)
			(layers "F.Cu" "F.Mask" "F.Paste")
			(net "GND")
		)
		(pad "DJ31" smd circle
			(at -13.008356 14.277086 270)
			(size 0.4318 0.4318)
			(layers "F.Cu" "F.Mask" "F.Paste")
			(net "GND")
		)
		(pad "DJ33" smd circle
			(at -11.380724 14.277086 270)
			(size 0.4318 0.4318)
			(layers "F.Cu" "F.Mask" "F.Paste")
			(net "M_G_CPU0_SB_DQS_DN<0>")
		)
		(pad "DJ35" smd circle
			(at -9.752838 14.277086 270)
			(size 0.4318 0.4318)
			(layers "F.Cu" "F.Mask" "F.Paste")
			(net "GND")
		)
		(pad "DJ37" smd circle
			(at -8.124952 14.277086 270)
			(size 0.4318 0.4318)
			(layers "F.Cu" "F.Mask" "F.Paste")
			(net "GND")
		)
		(pad "DJ39" smd circle
			(at -6.49732 14.277086 270)
			(size 0.4318 0.4318)
			(layers "F.Cu" "F.Mask" "F.Paste")
			(net "M_H_CPU0_SB_CA<6>")
		)
		(pad "DJ41" smd circle
			(at -4.869434 14.277086 270)
			(size 0.4318 0.4318)
			(layers "F.Cu" "F.Mask" "F.Paste")
			(net "GND")
		)
		(pad "DJ43" smd circle
			(at -3.241802 14.277086 270)
			(size 0.4318 0.4318)
			(layers "F.Cu" "F.Mask" "F.Paste")
			(net "GND")
		)
		(pad "DJ45" smd circle
			(at -1.613916 14.277086 270)
			(size 0.4318 0.4318)
			(layers "F.Cu" "F.Mask" "F.Paste")
			(net "M_G_CPU0_CLK_DP<1>")
		)
		(pad "DJ48" smd circle
			(at 2.427732 14.387068 270)
			(size 0.4318 0.4318)
			(layers "F.Cu" "F.Mask" "F.Paste")
			(net "GND")
		)
		(pad "DJ50" smd circle
			(at 4.055618 14.387068 270)
			(size 0.4318 0.4318)
			(layers "F.Cu" "F.Mask" "F.Paste")
			(net "GND")
		)
		(pad "DJ52" smd circle
			(at 5.68325 14.387068 270)
			(size 0.4318 0.4318)
			(layers "F.Cu" "F.Mask" "F.Paste")
			(net "M_G_CPU0_SA_CA<0>")
		)
		(pad "DJ54" smd circle
			(at 7.311136 14.387068 270)
			(size 0.4318 0.4318)
			(layers "F.Cu" "F.Mask" "F.Paste")
			(net "GND")
		)
		(pad "DJ56" smd circle
			(at 8.939022 14.387068 270)
			(size 0.4318 0.4318)
			(layers "F.Cu" "F.Mask" "F.Paste")
			(net "GND")
		)
		(pad "DJ58" smd circle
			(at 10.566654 14.387068 270)
			(size 0.4318 0.4318)
			(layers "F.Cu" "F.Mask" "F.Paste")
			(net "M_G_CPU0_SA_DQS_DP<4>")
		)
		(pad "DJ60" smd circle
			(at 12.19454 14.387068 270)
			(size 0.4318 0.4318)
			(layers "F.Cu" "F.Mask" "F.Paste")
			(net "GND")
		)
		(pad "DJ62" smd circle
			(at 13.822426 14.387068 270)
			(size 0.4318 0.4318)
			(layers "F.Cu" "F.Mask" "F.Paste")
			(net "GND")
		)
		(pad "DJ64" smd circle
			(at 15.450058 14.387068 270)
			(size 0.4318 0.4318)
			(layers "F.Cu" "F.Mask" "F.Paste")
			(net "M_G_CPU0_SA_DQS_DP<3>")
		)
		(pad "DJ66" smd circle
			(at 17.07769 14.387068 270)
			(size 0.4318 0.4318)
			(layers "F.Cu" "F.Mask" "F.Paste")
			(net "GND")
		)
		(pad "DJ68" smd circle
			(at 18.705576 14.387068 270)
			(size 0.4318 0.4318)
			(layers "F.Cu" "F.Mask" "F.Paste")
			(net "GND")
		)
		(pad "DJ70" smd circle
			(at 20.333462 14.387068 270)
			(size 0.4318 0.4318)
			(layers "F.Cu" "F.Mask" "F.Paste")
			(net "M_G_CPU0_SA_DQS_DN<1>")
		)
		(pad "DJ72" smd circle
			(at 21.961094 14.387068 270)
			(size 0.4318 0.4318)
			(layers "F.Cu" "F.Mask" "F.Paste")
			(net "GND")
		)
		(pad "DJ74" smd circle
			(at 23.58898 14.387068 270)
			(size 0.4318 0.4318)
			(layers "F.Cu" "F.Mask" "F.Paste")
			(net "GND")
		)
		(pad "DJ76" smd circle
			(at 25.216612 14.387068 270)
			(size 0.4318 0.4318)
			(layers "F.Cu" "F.Mask" "F.Paste")
			(net "M_H_CPU0_SA_DQS_DN<0>")
		)
		(pad "DJ78" smd circle
			(at 26.844498 14.387068 270)
			(size 0.4318 0.4318)
			(layers "F.Cu" "F.Mask" "F.Paste")
			(net "GND")
		)
		(pad "DJ80" smd circle
			(at 28.472384 14.387068 270)
			(size 0.4318 0.4318)
			(layers "F.Cu" "F.Mask" "F.Paste")
			(net "GND")
		)
		(pad "DJ82" smd circle
			(at 30.100016 14.387068 270)
			(size 0.4318 0.4318)
			(layers "F.Cu" "F.Mask" "F.Paste")
			(net "GND")
		)
		(pad "DJ84" smd circle
			(at 31.727902 14.387068 270)
			(size 0.4318 0.4318)
			(layers "F.Cu" "F.Mask" "F.Paste")
			(net "GND")
		)
		(pad "DJ86" smd circle
			(at 33.355534 14.387068 270)
			(size 0.4318 0.4318)
			(layers "F.Cu" "F.Mask" "F.Paste")
			(net "P5E_CPU0_PE3_TX_DP<8>")
		)
		(pad "DJ88" smd circle
			(at 34.98342 14.387068 270)
			(size 0.4318 0.4318)
			(layers "F.Cu" "F.Mask" "F.Paste")
			(net "GND")
		)
		(pad "DJ90" smd circle
			(at 36.611306 14.387068 270)
			(size 0.4318 0.4318)
			(layers "F.Cu" "F.Mask" "F.Paste")
			(net "P5E_CPU0_PE3_RX_DP<9>")
		)
		(pad "DK2" smd circle
			(at -36.611306 14.746732 270)
			(size 0.4318 0.4318)
			(layers "F.Cu" "F.Mask" "F.Paste")
			(net "UPI_CPU1_CPU0_P0P1_DP<9>")
		)
		(pad "DK4" smd circle
			(at -34.98342 14.746732 270)
			(size 0.4318 0.4318)
			(layers "F.Cu" "F.Mask" "F.Paste")
			(net "GND")
		)
		(pad "DK6" smd circle
			(at -33.355534 14.746732 270)
			(size 0.4318 0.4318)
			(layers "F.Cu" "F.Mask" "F.Paste")
			(net "UPI_CPU0_CPU1_P1P0_DN<8>")
		)
		(pad "DK8" smd circle
			(at -31.727902 14.746732 270)
			(size 0.4318 0.4318)
			(layers "F.Cu" "F.Mask" "F.Paste")
			(net "GND")
		)
		(pad "DK10" smd circle
			(at -30.100016 14.746732 270)
			(size 0.4318 0.4318)
			(layers "F.Cu" "F.Mask" "F.Paste")
			(net "P5E_CPU0_PE2_RX_DP<6>")
		)
		(pad "DK12" smd circle
			(at -28.472384 14.746732 270)
			(size 0.4318 0.4318)
			(layers "F.Cu" "F.Mask" "F.Paste")
			(net "GND")
		)
		(pad "DK14" smd circle
			(at -26.844498 14.746732 270)
			(size 0.4318 0.4318)
			(layers "F.Cu" "F.Mask" "F.Paste")
			(net "P5E_CPU0_PE2_TX_DN<7>")
		)
		(pad "DK16" smd circle
			(at -25.216612 14.746732 270)
			(size 0.4318 0.4318)
			(layers "F.Cu" "F.Mask" "F.Paste")
			(net "GND")
		)
		(pad "DK18" smd circle
			(at -23.58898 14.746732 270)
			(size 0.4318 0.4318)
			(layers "F.Cu" "F.Mask" "F.Paste")
			(net "GND")
		)
		(pad "DK20" smd circle
			(at -21.961094 14.746732 270)
			(size 0.4318 0.4318)
			(layers "F.Cu" "F.Mask" "F.Paste")
			(net "M_H_CPU0_SB_DQ<20>")
		)
	)
)
